# S9S_MB_2U (Grand Teton) — schematic netlist excerpt (pin names and nets, part order shuffled) for the footprints in the layout excerpt that follows; sources: Cadence DE-HDL packaged netlist, KiCad conversion of 03242023_DA0F0TMBIJ0_F0T_Motherboard_J_brd_V01_OCP.brd

R861  Q_RES  0 5% CHIP  pkg 0402LF  page 128 : A = RST_CPU1_DRAM_EF_N ; B = RST_CPU1_DRAM_EF_PLD_N
R1331  Q_RES  4.7K 5% EMPTY  pkg 0402LF  page 243 : A = P3V3_AUX ; B = SMB_FRU_3V3AUX_SCL

(kicad_pcb
	(version 20260206)
	(generator "pcbnew")
	(generator_version "10.0")
	(general
		(thickness 1.6)
		(legacy_teardrops no)
	)
	(paper "A4")
	(title_block
		(title "03242023_DA0F0TMBIJ0_F0T_Motherboard_J_brd_V01_OCP.brd")
		(comment 1 "Grand Teton / footprints 3442-3443 of 6105")
	)
	(layers
		(0 "F.Cu" signal "TOP")
		(4 "In1.Cu" signal "GND")
		(6 "In2.Cu" signal "IN1")
		(8 "In3.Cu" signal "GND1")
		(10 "In4.Cu" signal "IN2")
		(12 "In5.Cu" signal "GND2")
		(14 "In6.Cu" signal "IN3")
		(16 "In7.Cu" signal "GND3")
		(18 "In8.Cu" signal "VCC")
		(20 "In9.Cu" signal "VCC1")
		(22 "In10.Cu" signal "GND4")
		(24 "In11.Cu" signal "IN4")
		(26 "In12.Cu" signal "GND5")
		(28 "In13.Cu" signal "IN5")
		(30 "In14.Cu" signal "GND6")
		(32 "In15.Cu" signal "IN6")
		(34 "In16.Cu" signal "GND7")
		(2 "B.Cu" signal "BOTTOM")
		(9 "F.Adhes" user "F.Adhesive")
		(11 "B.Adhes" user "B.Adhesive")
		(13 "F.Paste" user "Package Geometry/Pastemask Top")
		(15 "B.Paste" user "Package Geometry/Pastemask Bottom")
		(5 "F.SilkS" user "Ref Des/Silkscreen Top")
		(7 "B.SilkS" user "Ref Des/Silkscreen Bottom")
		(1 "F.Mask" user "Board Geometry/Soldermask Top")
		(3 "B.Mask" user "Board Geometry/Soldermask Bottom")
		(17 "Dwgs.User" user "User.Drawings")
		(19 "Cmts.User" user "User.Comments")
		(21 "Eco1.User" user "User.Eco1")
		(23 "Eco2.User" user "User.Eco2")
		(25 "Edge.Cuts" user "Board Geometry/Outline")
		(27 "Margin" user)
		(31 "F.CrtYd" user "Package Geometry/Place Bound Top")
		(29 "B.CrtYd" user "Package Geometry/Place Bound Bottom")
		(35 "F.Fab" user "Ref Des/Assembly Top")
		(33 "B.Fab" user "Ref Des/Assembly Bottom")
	)
	(footprint ""
		(layer "F.Cu")
		(at 125.264926 -119.810784 -90)
		(property "Reference" "R861"
			(at 0 0 270)
			(layer "F.SilkS")
			(hide yes)
			(effects
				(font
					(size 1.27 1.27)
				)
			)
		)
		(property "Value" ""
			(at 0 0 270)
			(layer "F.Fab")
			(effects
				(font
					(size 1.27 1.27)
				)
			)
		)
		(duplicate_pad_numbers_are_jumpers no)
		(fp_line
			(start -0.7874 0.4064)
			(end -0.7874 -0.4064)
			(stroke
				(width 0.1524)
				(type default)
			)
			(layer "F.SilkS")
		)
		(fp_line
			(start 0.7874 0.4064)
			(end -0.7874 0.4064)
			(stroke
				(width 0.1524)
				(type default)
			)
			(layer "F.SilkS")
		)
		(fp_line
			(start -0.7874 -0.4064)
			(end 0.7874 -0.4064)
			(stroke
				(width 0.1524)
				(type default)
			)
			(layer "F.SilkS")
		)
		(fp_line
			(start 0.7874 -0.4064)
			(end 0.7874 0.4064)
			(stroke
				(width 0.1524)
				(type default)
			)
			(layer "F.SilkS")
		)
		(fp_line
			(start -0.67945 0.3048)
			(end -0.67945 -0.305054)
			(stroke
				(width 0.1)
				(type default)
			)
			(layer "F.Fab")
		)
		(fp_line
			(start -0.12065 0.3048)
			(end -0.67945 0.3048)
			(stroke
				(width 0.1)
				(type default)
			)
			(layer "F.Fab")
		)
		(fp_line
			(start 0.120396 0.3048)
			(end 0.120396 0.2794)
			(stroke
				(width 0.1)
				(type default)
			)
			(layer "F.Fab")
		)
		(fp_line
			(start 0.67945 0.3048)
			(end 0.120396 0.3048)
			(stroke
				(width 0.1)
				(type default)
			)
			(layer "F.Fab")
		)
		(fp_line
			(start -0.12065 0.2794)
			(end -0.12065 0.3048)
			(stroke
				(width 0.1)
				(type default)
			)
			(layer "F.Fab")
		)
		(fp_line
			(start 0.120396 0.2794)
			(end -0.12065 0.2794)
			(stroke
				(width 0.1)
				(type default)
			)
			(layer "F.Fab")
		)
		(fp_line
			(start -0.12065 -0.2794)
			(end 0.12065 -0.2794)
			(stroke
				(width 0.1)
				(type default)
			)
			(layer "F.Fab")
		)
		(fp_line
			(start 0.12065 -0.2794)
			(end 0.12065 -0.3048)
			(stroke
				(width 0.1)
				(type default)
			)
			(layer "F.Fab")
		)
		(fp_line
			(start 0.12065 -0.3048)
			(end 0.67945 -0.3048)
			(stroke
				(width 0.1)
				(type default)
			)
			(layer "F.Fab")
		)
		(fp_line
			(start 0.67945 -0.3048)
			(end 0.67945 0.3048)
			(stroke
				(width 0.1)
				(type default)
			)
			(layer "F.Fab")
		)
		(fp_line
			(start -0.67945 -0.305054)
			(end -0.12065 -0.305054)
			(stroke
				(width 0.1)
				(type default)
			)
			(layer "F.Fab")
		)
		(fp_line
			(start -0.12065 -0.305054)
			(end -0.12065 -0.2794)
			(stroke
				(width 0.1)
				(type default)
			)
			(layer "F.Fab")
		)
		(pad "1" smd circle
			(at -0.40005 0 270)
			(size 0 0)
			(layers "F.Cu" "F.Mask" "F.Paste")
			(net "RST_CPU1_DRAM_EF_N")
		)
		(pad "2" smd circle
			(at 0.40005 0 270)
			(size 0 0)
			(layers "F.Cu" "F.Mask" "F.Paste")
			(net "RST_CPU1_DRAM_EF_PLD_N")
		)
	)
	(footprint ""
		(layer "F.Cu")
		(at 292.61054 -93.482414 180)
		(property "Reference" "R1331"
			(at 0 0 180)
			(layer "F.SilkS")
			(hide yes)
			(effects
				(font
					(size 1.27 1.27)
				)
			)
		)
		(property "Value" ""
			(at 0 0 180)
			(layer "F.Fab")
			(effects
				(font
					(size 1.27 1.27)
				)
			)
		)
		(duplicate_pad_numbers_are_jumpers no)
		(fp_line
			(start 0.7874 0.4064)
			(end -0.7874 0.4064)
			(stroke
				(width 0.1524)
				(type default)
			)
			(layer "F.SilkS")
		)
		(fp_line
			(start 0.7874 -0.4064)
			(end 0.7874 0.4064)
			(stroke
				(width 0.1524)
				(type default)
			)
			(layer "F.SilkS")
		)
		(fp_line
			(start -0.7874 0.4064)
			(end -0.7874 -0.4064)
			(stroke
				(width 0.1524)
				(type default)
			)
			(layer "F.SilkS")
		)
		(fp_line
			(start -0.7874 -0.4064)
			(end 0.7874 -0.4064)
			(stroke
				(width 0.1524)
				(type default)
			)
			(layer "F.SilkS")
		)
		(fp_line
			(start 0.67945 0.3048)
			(end 0.120396 0.3048)
			(stroke
				(width 0.1)
				(type default)
			)
			(layer "F.Fab")
		)
		(fp_line
			(start 0.67945 -0.3048)
			(end 0.67945 0.3048)
			(stroke
				(width 0.1)
				(type default)
			)
			(layer "F.Fab")
		)
		(fp_line
			(start 0.12065 -0.2794)
			(end 0.12065 -0.3048)
			(stroke
				(width 0.1)
				(type default)
			)
			(layer "F.Fab")
		)
		(fp_line
			(start 0.12065 -0.3048)
			(end 0.67945 -0.3048)
			(stroke
				(width 0.1)
				(type default)
			)
			(layer "F.Fab")
		)
		(fp_line
			(start 0.120396 0.3048)
			(end 0.120396 0.2794)
			(stroke
				(width 0.1)
				(type default)
			)
			(layer "F.Fab")
		)
		(fp_line
			(start 0.120396 0.2794)
			(end -0.12065 0.2794)
			(stroke
				(width 0.1)
				(type default)
			)
			(layer "F.Fab")
		)
		(fp_line
			(start -0.12065 0.3048)
			(end -0.67945 0.3048)
			(stroke
				(width 0.1)
				(type default)
			)
			(layer "F.Fab")
		)
		(fp_line
			(start -0.12065 0.2794)
			(end -0.12065 0.3048)
			(stroke
				(width 0.1)
				(type default)
			)
			(layer "F.Fab")
		)
		(fp_line
			(start -0.12065 -0.2794)
			(end 0.12065 -0.2794)
			(stroke
				(width 0.1)
				(type default)
			)
			(layer "F.Fab")
		)
		(fp_line
			(start -0.12065 -0.305054)
			(end -0.12065 -0.2794)
			(stroke
				(width 0.1)
				(type default)
			)
			(layer "F.Fab")
		)
		(fp_line
			(start -0.67945 0.3048)
			(end -0.67945 -0.305054)
			(stroke
				(width 0.1)
				(type default)
			)
			(layer "F.Fab")
		)
		(fp_line
			(start -0.67945 -0.305054)
			(end -0.12065 -0.305054)
			(stroke
				(width 0.1)
				(type default)
			)
			(layer "F.Fab")
		)
		(pad "1" smd circle
			(at -0.40005 0 180)
			(size 0 0)
			(layers "F.Cu" "F.Mask" "F.Paste")
			(net "P3V3_AUX")
		)
		(pad "2" smd circle
			(at 0.40005 0 180)
			(size 0 0)
			(layers "F.Cu" "F.Mask" "F.Paste")
			(net "SMB_FRU_3V3AUX_SCL")
		)
	)
)
